(kicad_pcb
	(version 20260206)
	(generator "pcbnew")
	(generator_version "10.0")
	(general
		(thickness 1.6)
		(legacy_teardrops no)
	)
	(paper "A4")
	(title_block
		(title "01162023_DA0F0TEBIF0_F0T_Expander_BD_F_brd_V02_OCP.brd")
		(comment 1 "Grand Teton / footprints 988-994 of 9728")
	)
	(layers
		(0 "F.Cu" signal "TOP")
		(4 "In1.Cu" signal "GND")
		(6 "In2.Cu" signal "VCC")
		(8 "In3.Cu" signal "VCC1")
		(10 "In4.Cu" signal "GND1")
		(12 "In5.Cu" signal "IN1")
		(14 "In6.Cu" signal "GND2")
		(16 "In7.Cu" signal "IN2")
		(18 "In8.Cu" signal "GND3")
		(20 "In9.Cu" signal "IN3")
		(22 "In10.Cu" signal "GND4")
		(24 "In11.Cu" signal "IN4")
		(26 "In12.Cu" signal "GND5")
		(28 "In13.Cu" signal "IN5")
		(30 "In14.Cu" signal "GND6")
		(32 "In15.Cu" signal "IN6")
		(34 "In16.Cu" signal "GND7")
		(2 "B.Cu" signal "BOTTOM")
		(9 "F.Adhes" user "F.Adhesive")
		(11 "B.Adhes" user "B.Adhesive")
		(13 "F.Paste" user "Package Geometry/Pastemask Top")
		(15 "B.Paste" user "Package Geometry/Pastemask Bottom")
		(5 "F.SilkS" user "Ref Des/Silkscreen Top")
		(7 "B.SilkS" user "Ref Des/Silkscreen Bottom")
		(1 "F.Mask" user "Board Geometry/Soldermask Top")
		(3 "B.Mask" user "Board Geometry/Soldermask Bottom")
		(17 "Dwgs.User" user "User.Drawings")
		(19 "Cmts.User" user "User.Comments")
		(21 "Eco1.User" user "User.Eco1")
		(23 "Eco2.User" user "User.Eco2")
		(25 "Edge.Cuts" user "Board Geometry/Outline")
		(27 "Margin" user)
		(31 "F.CrtYd" user "Package Geometry/Place Bound Top")
		(29 "B.CrtYd" user "Package Geometry/Place Bound Bottom")
		(35 "F.Fab" user "Ref Des/Assembly Top")
		(33 "B.Fab" user "Ref Des/Assembly Bottom")
	)
	(footprint ""
		(layer "F.Cu")
		(at 28.1051 -307.084984 45)
		(property "Reference" "R1167"
			(at 0 0 45)
			(layer "F.SilkS")
			(hide yes)
			(effects
				(font
					(size 1.27 1.27)
				)
			)
		)
		(property "Value" ""
			(at 0 0 45)
			(layer "F.Fab")
			(effects
				(font
					(size 1.27 1.27)
				)
			)
		)
		(duplicate_pad_numbers_are_jumpers no)
		(fp_line
			(start -0.787389 -0.406267)
			(end 0.787389 -0.406267)
			(stroke
				(width 0.1524)
				(type default)
			)
			(layer "F.SilkS")
		)
		(fp_line
			(start -0.787389 0.406267)
			(end -0.787389 -0.406267)
			(stroke
				(width 0.1524)
				(type default)
			)
			(layer "F.SilkS")
		)
		(fp_line
			(start 0.787389 -0.406267)
			(end 0.787389 0.406267)
			(stroke
				(width 0.1524)
				(type default)
			)
			(layer "F.SilkS")
		)
		(fp_line
			(start 0.787389 0.406267)
			(end -0.787389 0.406267)
			(stroke
				(width 0.1524)
				(type default)
			)
			(layer "F.SilkS")
		)
		(fp_line
			(start -0.679446 -0.305149)
			(end -0.120695 -0.304969)
			(stroke
				(width 0.1)
				(type default)
			)
			(layer "F.Fab")
		)
		(fp_line
			(start -0.120695 -0.304969)
			(end -0.120695 -0.279466)
			(stroke
				(width 0.1)
				(type default)
			)
			(layer "F.Fab")
		)
		(fp_line
			(start -0.120695 -0.279466)
			(end 0.120695 -0.279466)
			(stroke
				(width 0.1)
				(type default)
			)
			(layer "F.Fab")
		)
		(fp_line
			(start -0.679446 0.30479)
			(end -0.679446 -0.305149)
			(stroke
				(width 0.1)
				(type default)
			)
			(layer "F.Fab")
		)
		(fp_line
			(start 0.120515 -0.30479)
			(end 0.679446 -0.30479)
			(stroke
				(width 0.1)
				(type default)
			)
			(layer "F.Fab")
		)
		(fp_line
			(start 0.120695 -0.279466)
			(end 0.120515 -0.30479)
			(stroke
				(width 0.1)
				(type default)
			)
			(layer "F.Fab")
		)
		(fp_line
			(start -0.120695 0.279466)
			(end -0.120515 0.30479)
			(stroke
				(width 0.1)
				(type default)
			)
			(layer "F.Fab")
		)
		(fp_line
			(start -0.120515 0.30479)
			(end -0.679446 0.30479)
			(stroke
				(width 0.1)
				(type default)
			)
			(layer "F.Fab")
		)
		(fp_line
			(start 0.679446 -0.30479)
			(end 0.679446 0.30479)
			(stroke
				(width 0.1)
				(type default)
			)
			(layer "F.Fab")
		)
		(fp_line
			(start 0.120335 0.279466)
			(end -0.120695 0.279466)
			(stroke
				(width 0.1)
				(type default)
			)
			(layer "F.Fab")
		)
		(fp_line
			(start 0.120515 0.30479)
			(end 0.120335 0.279466)
			(stroke
				(width 0.1)
				(type default)
			)
			(layer "F.Fab")
		)
		(fp_line
			(start 0.679446 0.30479)
			(end 0.120515 0.30479)
			(stroke
				(width 0.1)
				(type default)
			)
			(layer "F.Fab")
		)
		(pad "1" smd circle
			(at -0.40005 0 45)
			(size 0 0)
			(layers "F.Cu" "F.Mask" "F.Paste")
			(net "GND")
		)
		(pad "2" smd circle
			(at 0.40005 0 45)
			(size 0 0)
			(layers "F.Cu" "F.Mask" "F.Paste")
			(net "PEX0_DBG_SEL0")
		)
	)
	(footprint ""
		(layer "F.Cu")
		(at 349.722694 -293.816786 -90)
		(property "Reference" "PC163"
			(at 0 0 270)
			(layer "F.SilkS")
			(hide yes)
			(effects
				(font
					(size 1.27 1.27)
				)
			)
		)
		(property "Value" ""
			(at 0 0 270)
			(layer "F.Fab")
			(effects
				(font
					(size 1.27 1.27)
				)
			)
		)
		(duplicate_pad_numbers_are_jumpers no)
		(fp_line
			(start -0.7874 0.4064)
			(end -0.7874 -0.4064)
			(stroke
				(width 0.1524)
				(type default)
			)
			(layer "F.SilkS")
		)
		(fp_line
			(start 0.7874 0.4064)
			(end -0.7874 0.4064)
			(stroke
				(width 0.1524)
				(type default)
			)
			(layer "F.SilkS")
		)
		(fp_line
			(start -0.7874 -0.4064)
			(end 0.7874 -0.4064)
			(stroke
				(width 0.1524)
				(type default)
			)
			(layer "F.SilkS")
		)
		(fp_line
			(start 0.7874 -0.4064)
			(end 0.7874 0.4064)
			(stroke
				(width 0.1524)
				(type default)
			)
			(layer "F.SilkS")
		)
		(fp_line
			(start -0.67945 0.3048)
			(end -0.67945 -0.305054)
			(stroke
				(width 0.1)
				(type default)
			)
			(layer "F.Fab")
		)
		(fp_line
			(start -0.12065 0.3048)
			(end -0.67945 0.3048)
			(stroke
				(width 0.1)
				(type default)
			)
			(layer "F.Fab")
		)
		(fp_line
			(start 0.120396 0.3048)
			(end 0.120396 0.2794)
			(stroke
				(width 0.1)
				(type default)
			)
			(layer "F.Fab")
		)
		(fp_line
			(start 0.67945 0.3048)
			(end 0.120396 0.3048)
			(stroke
				(width 0.1)
				(type default)
			)
			(layer "F.Fab")
		)
		(fp_line
			(start -0.12065 0.2794)
			(end -0.12065 0.3048)
			(stroke
				(width 0.1)
				(type default)
			)
			(layer "F.Fab")
		)
		(fp_line
			(start 0.120396 0.2794)
			(end -0.12065 0.2794)
			(stroke
				(width 0.1)
				(type default)
			)
			(layer "F.Fab")
		)
		(fp_line
			(start -0.12065 -0.2794)
			(end 0.12065 -0.2794)
			(stroke
				(width 0.1)
				(type default)
			)
			(layer "F.Fab")
		)
		(fp_line
			(start 0.12065 -0.2794)
			(end 0.12065 -0.3048)
			(stroke
				(width 0.1)
				(type default)
			)
			(layer "F.Fab")
		)
		(fp_line
			(start 0.12065 -0.3048)
			(end 0.67945 -0.3048)
			(stroke
				(width 0.1)
				(type default)
			)
			(layer "F.Fab")
		)
		(fp_line
			(start 0.67945 -0.3048)
			(end 0.67945 0.3048)
			(stroke
				(width 0.1)
				(type default)
			)
			(layer "F.Fab")
		)
		(fp_line
			(start -0.67945 -0.305054)
			(end -0.12065 -0.305054)
			(stroke
				(width 0.1)
				(type default)
			)
			(layer "F.Fab")
		)
		(fp_line
			(start -0.12065 -0.305054)
			(end -0.12065 -0.2794)
			(stroke
				(width 0.1)
				(type default)
			)
			(layer "F.Fab")
		)
		(pad "1" smd circle
			(at -0.40005 0 270)
			(size 0 0)
			(layers "F.Cu" "F.Mask" "F.Paste")
			(net "P0V8_PEX2")
		)
		(pad "2" smd circle
			(at 0.40005 0 270)
			(size 0 0)
			(layers "F.Cu" "F.Mask" "F.Paste")
			(net "GND")
		)
	)
	(footprint ""
		(layer "F.Cu")
		(at 80.019398 -153.390346 180)
		(property "Reference" "C4"
			(at 0 0 180)
			(layer "F.SilkS")
			(hide yes)
			(effects
				(font
					(size 1.27 1.27)
				)
			)
		)
		(property "Value" ""
			(at 0 0 180)
			(layer "F.Fab")
			(effects
				(font
					(size 1.27 1.27)
				)
			)
		)
		(duplicate_pad_numbers_are_jumpers no)
		(fp_line
			(start 0.299974 0.150114)
			(end -0.299974 0.150114)
			(stroke
				(width 0.1)
				(type default)
			)
			(layer "F.Fab")
		)
		(fp_line
			(start 0.299974 -0.150114)
			(end 0.299974 0.150114)
			(stroke
				(width 0.1)
				(type default)
			)
			(layer "F.Fab")
		)
		(fp_line
			(start -0.299974 0.150114)
			(end -0.299974 -0.150114)
			(stroke
				(width 0.1)
				(type default)
			)
			(layer "F.Fab")
		)
		(fp_line
			(start -0.299974 -0.150114)
			(end 0.299974 -0.150114)
			(stroke
				(width 0.1)
				(type default)
			)
			(layer "F.Fab")
		)
		(pad "1" smd rect
			(at -0.2667 0 180)
			(size 0.3048 0.381)
			(layers "F.Cu" "F.Mask" "F.Paste")
			(net "P5E_PEX0_STN0_TX_DP<14>")
		)
		(pad "2" smd rect
			(at 0.2667 0 180)
			(size 0.3048 0.381)
			(layers "F.Cu" "F.Mask" "F.Paste")
			(net "P5E_PEX0_STN0_TX_C_DP<14>")
		)
	)
	(footprint ""
		(layer "F.Cu")
		(at 353.174554 -279.101804)
		(property "Reference" "PC171"
			(at 0 0 0)
			(layer "F.SilkS")
			(hide yes)
			(effects
				(font
					(size 1.27 1.27)
				)
			)
		)
		(property "Value" ""
			(at 0 0 0)
			(layer "F.Fab")
			(effects
				(font
					(size 1.27 1.27)
				)
			)
		)
		(duplicate_pad_numbers_are_jumpers no)
		(fp_line
			(start -0.7874 -0.4064)
			(end 0.7874 -0.4064)
			(stroke
				(width 0.1524)
				(type default)
			)
			(layer "F.SilkS")
		)
		(fp_line
			(start -0.7874 0.4064)
			(end -0.7874 -0.4064)
			(stroke
				(width 0.1524)
				(type default)
			)
			(layer "F.SilkS")
		)
		(fp_line
			(start 0.7874 -0.4064)
			(end 0.7874 0.4064)
			(stroke
				(width 0.1524)
				(type default)
			)
			(layer "F.SilkS")
		)
		(fp_line
			(start 0.7874 0.4064)
			(end -0.7874 0.4064)
			(stroke
				(width 0.1524)
				(type default)
			)
			(layer "F.SilkS")
		)
		(fp_line
			(start -0.67945 -0.305054)
			(end -0.12065 -0.305054)
			(stroke
				(width 0.1)
				(type default)
			)
			(layer "F.Fab")
		)
		(fp_line
			(start -0.67945 0.3048)
			(end -0.67945 -0.305054)
			(stroke
				(width 0.1)
				(type default)
			)
			(layer "F.Fab")
		)
		(fp_line
			(start -0.12065 -0.305054)
			(end -0.12065 -0.2794)
			(stroke
				(width 0.1)
				(type default)
			)
			(layer "F.Fab")
		)
		(fp_line
			(start -0.12065 -0.2794)
			(end 0.12065 -0.2794)
			(stroke
				(width 0.1)
				(type default)
			)
			(layer "F.Fab")
		)
		(fp_line
			(start -0.12065 0.2794)
			(end -0.12065 0.3048)
			(stroke
				(width 0.1)
				(type default)
			)
			(layer "F.Fab")
		)
		(fp_line
			(start -0.12065 0.3048)
			(end -0.67945 0.3048)
			(stroke
				(width 0.1)
				(type default)
			)
			(layer "F.Fab")
		)
		(fp_line
			(start 0.120396 0.2794)
			(end -0.12065 0.2794)
			(stroke
				(width 0.1)
				(type default)
			)
			(layer "F.Fab")
		)
		(fp_line
			(start 0.120396 0.3048)
			(end 0.120396 0.2794)
			(stroke
				(width 0.1)
				(type default)
			)
			(layer "F.Fab")
		)
		(fp_line
			(start 0.12065 -0.3048)
			(end 0.67945 -0.3048)
			(stroke
				(width 0.1)
				(type default)
			)
			(layer "F.Fab")
		)
		(fp_line
			(start 0.12065 -0.2794)
			(end 0.12065 -0.3048)
			(stroke
				(width 0.1)
				(type default)
			)
			(layer "F.Fab")
		)
		(fp_line
			(start 0.67945 -0.3048)
			(end 0.67945 0.3048)
			(stroke
				(width 0.1)
				(type default)
			)
			(layer "F.Fab")
		)
		(fp_line
			(start 0.67945 0.3048)
			(end 0.120396 0.3048)
			(stroke
				(width 0.1)
				(type default)
			)
			(layer "F.Fab")
		)
		(pad "1" smd circle
			(at -0.40005 0)
			(size 0 0)
			(layers "F.Cu" "F.Mask" "F.Paste")
			(net "SW_P12V_P0V8_PEX3_FLT")
		)
		(pad "2" smd circle
			(at 0.40005 0)
			(size 0 0)
			(layers "F.Cu" "F.Mask" "F.Paste")
			(net "GND")
		)
	)
	(footprint ""
		(layer "F.Cu")
		(at 322.051934 -289.230816 90)
		(property "Reference" "R3986"
			(at 0 0 90)
			(layer "F.SilkS")
			(hide yes)
			(effects
				(font
					(size 1.27 1.27)
				)
			)
		)
		(property "Value" ""
			(at 0 0 90)
			(layer "F.Fab")
			(effects
				(font
					(size 1.27 1.27)
				)
			)
		)
		(duplicate_pad_numbers_are_jumpers no)
		(fp_line
			(start 0.7874 -0.4064)
			(end 0.7874 0.4064)
			(stroke
				(width 0.1524)
				(type default)
			)
			(layer "F.SilkS")
		)
		(fp_line
			(start -0.7874 -0.4064)
			(end 0.7874 -0.4064)
			(stroke
				(width 0.1524)
				(type default)
			)
			(layer "F.SilkS")
		)
		(fp_line
			(start 0.7874 0.4064)
			(end -0.7874 0.4064)
			(stroke
				(width 0.1524)
				(type default)
			)
			(layer "F.SilkS")
		)
		(fp_line
			(start -0.7874 0.4064)
			(end -0.7874 -0.4064)
			(stroke
				(width 0.1524)
				(type default)
			)
			(layer "F.SilkS")
		)
		(fp_line
			(start -0.12065 -0.305054)
			(end -0.12065 -0.2794)
			(stroke
				(width 0.1)
				(type default)
			)
			(layer "F.Fab")
		)
		(fp_line
			(start -0.67945 -0.305054)
			(end -0.12065 -0.305054)
			(stroke
				(width 0.1)
				(type default)
			)
			(layer "F.Fab")
		)
		(fp_line
			(start 0.67945 -0.3048)
			(end 0.67945 0.3048)
			(stroke
				(width 0.1)
				(type default)
			)
			(layer "F.Fab")
		)
		(fp_line
			(start 0.12065 -0.3048)
			(end 0.67945 -0.3048)
			(stroke
				(width 0.1)
				(type default)
			)
			(layer "F.Fab")
		)
		(fp_line
			(start 0.12065 -0.2794)
			(end 0.12065 -0.3048)
			(stroke
				(width 0.1)
				(type default)
			)
			(layer "F.Fab")
		)
		(fp_line
			(start -0.12065 -0.2794)
			(end 0.12065 -0.2794)
			(stroke
				(width 0.1)
				(type default)
			)
			(layer "F.Fab")
		)
		(fp_line
			(start 0.120396 0.2794)
			(end -0.12065 0.2794)
			(stroke
				(width 0.1)
				(type default)
			)
			(layer "F.Fab")
		)
		(fp_line
			(start -0.12065 0.2794)
			(end -0.12065 0.3048)
			(stroke
				(width 0.1)
				(type default)
			)
			(layer "F.Fab")
		)
		(fp_line
			(start 0.67945 0.3048)
			(end 0.120396 0.3048)
			(stroke
				(width 0.1)
				(type default)
			)
			(layer "F.Fab")
		)
		(fp_line
			(start 0.120396 0.3048)
			(end 0.120396 0.2794)
			(stroke
				(width 0.1)
				(type default)
			)
			(layer "F.Fab")
		)
		(fp_line
			(start -0.12065 0.3048)
			(end -0.67945 0.3048)
			(stroke
				(width 0.1)
				(type default)
			)
			(layer "F.Fab")
		)
		(fp_line
			(start -0.67945 0.3048)
			(end -0.67945 -0.305054)
			(stroke
				(width 0.1)
				(type default)
			)
			(layer "F.Fab")
		)
		(pad "1" smd circle
			(at -0.40005 0 90)
			(size 0 0)
			(layers "F.Cu" "F.Mask" "F.Paste")
			(net "SMB_PEX2_FPGA_SDA")
		)
		(pad "2" smd circle
			(at 0.40005 0 90)
			(size 0 0)
			(layers "F.Cu" "F.Mask" "F.Paste")
			(net "SMB_PEX2_HOST_LS_SDA")
		)
	)
	(footprint ""
		(layer "F.Cu")
		(at 364.28807 -45.704252 90)
		(property "Reference" "R638"
			(at 0 0 90)
			(layer "F.SilkS")
			(hide yes)
			(effects
				(font
					(size 1.27 1.27)
				)
			)
		)
		(property "Value" ""
			(at 0 0 90)
			(layer "F.Fab")
			(effects
				(font
					(size 1.27 1.27)
				)
			)
		)
		(duplicate_pad_numbers_are_jumpers no)
		(fp_line
			(start 3.937508 -1.8796)
			(end -3.937508 -1.8796)
			(stroke
				(width 0.1524)
				(type default)
			)
			(layer "F.SilkS")
		)
		(fp_line
			(start -3.937508 -1.8796)
			(end -3.937508 1.8796)
			(stroke
				(width 0.1524)
				(type default)
			)
			(layer "F.SilkS")
		)
		(fp_line
			(start 3.937508 1.8796)
			(end 3.937508 -1.8796)
			(stroke
				(width 0.1524)
				(type default)
			)
			(layer "F.SilkS")
		)
		(fp_line
			(start -3.937508 1.8796)
			(end 3.937508 1.8796)
			(stroke
				(width 0.1524)
				(type default)
			)
			(layer "F.SilkS")
		)
		(fp_line
			(start 3.275076 -1.674876)
			(end -3.275076 -1.674876)
			(stroke
				(width 0.1)
				(type default)
			)
			(layer "F.Fab")
		)
		(fp_line
			(start -3.275076 -1.674876)
			(end -3.275076 1.674876)
			(stroke
				(width 0.1)
				(type default)
			)
			(layer "F.Fab")
		)
		(fp_line
			(start 3.275076 1.674876)
			(end 3.275076 -1.674876)
			(stroke
				(width 0.1)
				(type default)
			)
			(layer "F.Fab")
		)
		(fp_line
			(start -3.275076 1.674876)
			(end 3.275076 1.674876)
			(stroke
				(width 0.1)
				(type default)
			)
			(layer "F.Fab")
		)
		(pad "1" smd rect
			(at -2.350008 0 90)
			(size 2.921 3.5052)
			(layers "F.Cu" "F.Mask" "F.Paste")
			(net "P12V_SSD12")
		)
		(pad "2" smd rect
			(at 2.350008 0 90)
			(size 2.921 3.5052)
			(layers "F.Cu" "F.Mask" "F.Paste")
			(net "P12V_SSD12_R")
		)
	)
	(footprint ""
		(layer "F.Cu")
		(at 263.654286 -250.070874 -90)
		(property "Reference" "R1340"
			(at 0 0 270)
			(layer "F.SilkS")
			(hide yes)
			(effects
				(font
					(size 1.27 1.27)
				)
			)
		)
		(property "Value" ""
			(at 0 0 270)
			(layer "F.Fab")
			(effects
				(font
					(size 1.27 1.27)
				)
			)
		)
		(duplicate_pad_numbers_are_jumpers no)
		(fp_line
			(start -0.7874 0.4064)
			(end -0.7874 -0.4064)
			(stroke
				(width 0.1524)
				(type default)
			)
			(layer "F.SilkS")
		)
		(fp_line
			(start 0.7874 0.4064)
			(end -0.7874 0.4064)
			(stroke
				(width 0.1524)
				(type default)
			)
			(layer "F.SilkS")
		)
		(fp_line
			(start -0.7874 -0.4064)
			(end 0.7874 -0.4064)
			(stroke
				(width 0.1524)
				(type default)
			)
			(layer "F.SilkS")
		)
		(fp_line
			(start 0.7874 -0.4064)
			(end 0.7874 0.4064)
			(stroke
				(width 0.1524)
				(type default)
			)
			(layer "F.SilkS")
		)
		(fp_line
			(start -0.67945 0.3048)
			(end -0.67945 -0.305054)
			(stroke
				(width 0.1)
				(type default)
			)
			(layer "F.Fab")
		)
		(fp_line
			(start -0.12065 0.3048)
			(end -0.67945 0.3048)
			(stroke
				(width 0.1)
				(type default)
			)
			(layer "F.Fab")
		)
		(fp_line
			(start 0.120396 0.3048)
			(end 0.120396 0.2794)
			(stroke
				(width 0.1)
				(type default)
			)
			(layer "F.Fab")
		)
		(fp_line
			(start 0.67945 0.3048)
			(end 0.120396 0.3048)
			(stroke
				(width 0.1)
				(type default)
			)
			(layer "F.Fab")
		)
		(fp_line
			(start -0.12065 0.2794)
			(end -0.12065 0.3048)
			(stroke
				(width 0.1)
				(type default)
			)
			(layer "F.Fab")
		)
		(fp_line
			(start 0.120396 0.2794)
			(end -0.12065 0.2794)
			(stroke
				(width 0.1)
				(type default)
			)
			(layer "F.Fab")
		)
		(fp_line
			(start -0.12065 -0.2794)
			(end 0.12065 -0.2794)
			(stroke
				(width 0.1)
				(type default)
			)
			(layer "F.Fab")
		)
		(fp_line
			(start 0.12065 -0.2794)
			(end 0.12065 -0.3048)
			(stroke
				(width 0.1)
				(type default)
			)
			(layer "F.Fab")
		)
		(fp_line
			(start 0.12065 -0.3048)
			(end 0.67945 -0.3048)
			(stroke
				(width 0.1)
				(type default)
			)
			(layer "F.Fab")
		)
		(fp_line
			(start 0.67945 -0.3048)
			(end 0.67945 0.3048)
			(stroke
				(width 0.1)
				(type default)
			)
			(layer "F.Fab")
		)
		(fp_line
			(start -0.67945 -0.305054)
			(end -0.12065 -0.305054)
			(stroke
				(width 0.1)
				(type default)
			)
			(layer "F.Fab")
		)
		(fp_line
			(start -0.12065 -0.305054)
			(end -0.12065 -0.2794)
			(stroke
				(width 0.1)
				(type default)
			)
			(layer "F.Fab")
		)
		(pad "1" smd circle
			(at -0.40005 0 270)
			(size 0 0)
			(layers "F.Cu" "F.Mask" "F.Paste")
			(net "PEX2_MODE_SEL4")
		)
		(pad "2" smd circle
			(at 0.40005 0 270)
			(size 0 0)
			(layers "F.Cu" "F.Mask" "F.Paste")
			(net "P1V8_PEX")
		)
	)
)
